(kicad_pcb
	(version 20260206)
	(generator "pcbnew")
	(generator_version "10.0")
	(general
		(thickness 1.6)
		(legacy_teardrops no)
	)
	(paper "A4")
	(title_block
		(title "01162023_DA0F0TEBIF0_F0T_Expander_BD_F_brd_V02_OCP.brd")
		(comment 1 "Grand Teton / footprints 6015-6019 of 9728")
	)
	(layers
		(0 "F.Cu" signal "TOP")
		(4 "In1.Cu" signal "GND")
		(6 "In2.Cu" signal "VCC")
		(8 "In3.Cu" signal "VCC1")
		(10 "In4.Cu" signal "GND1")
		(12 "In5.Cu" signal "IN1")
		(14 "In6.Cu" signal "GND2")
		(16 "In7.Cu" signal "IN2")
		(18 "In8.Cu" signal "GND3")
		(20 "In9.Cu" signal "IN3")
		(22 "In10.Cu" signal "GND4")
		(24 "In11.Cu" signal "IN4")
		(26 "In12.Cu" signal "GND5")
		(28 "In13.Cu" signal "IN5")
		(30 "In14.Cu" signal "GND6")
		(32 "In15.Cu" signal "IN6")
		(34 "In16.Cu" signal "GND7")
		(2 "B.Cu" signal "BOTTOM")
		(9 "F.Adhes" user "F.Adhesive")
		(11 "B.Adhes" user "B.Adhesive")
		(13 "F.Paste" user "Package Geometry/Pastemask Top")
		(15 "B.Paste" user "Package Geometry/Pastemask Bottom")
		(5 "F.SilkS" user "Ref Des/Silkscreen Top")
		(7 "B.SilkS" user "Ref Des/Silkscreen Bottom")
		(1 "F.Mask" user "Board Geometry/Soldermask Top")
		(3 "B.Mask" user "Board Geometry/Soldermask Bottom")
		(17 "Dwgs.User" user "User.Drawings")
		(19 "Cmts.User" user "User.Comments")
		(21 "Eco1.User" user "User.Eco1")
		(23 "Eco2.User" user "User.Eco2")
		(25 "Edge.Cuts" user "Board Geometry/Outline")
		(27 "Margin" user)
		(31 "F.CrtYd" user "Package Geometry/Place Bound Top")
		(29 "B.CrtYd" user "Package Geometry/Place Bound Bottom")
		(35 "F.Fab" user "Ref Des/Assembly Top")
		(33 "B.Fab" user "Ref Des/Assembly Bottom")
	)
	(footprint ""
		(layer "F.Cu")
		(at 108.238544 -393.753594 180)
		(property "Reference" "C3636"
			(at 0 0 180)
			(layer "F.SilkS")
			(hide yes)
			(effects
				(font
					(size 1.27 1.27)
				)
			)
		)
		(property "Value" ""
			(at 0 0 180)
			(layer "F.Fab")
			(effects
				(font
					(size 1.27 1.27)
				)
			)
		)
		(duplicate_pad_numbers_are_jumpers no)
		(fp_line
			(start 0.7874 0.4064)
			(end -0.7874 0.4064)
			(stroke
				(width 0.1524)
				(type default)
			)
			(layer "F.SilkS")
		)
		(fp_line
			(start 0.7874 -0.4064)
			(end 0.7874 0.4064)
			(stroke
				(width 0.1524)
				(type default)
			)
			(layer "F.SilkS")
		)
		(fp_line
			(start -0.7874 0.4064)
			(end -0.7874 -0.4064)
			(stroke
				(width 0.1524)
				(type default)
			)
			(layer "F.SilkS")
		)
		(fp_line
			(start -0.7874 -0.4064)
			(end 0.7874 -0.4064)
			(stroke
				(width 0.1524)
				(type default)
			)
			(layer "F.SilkS")
		)
		(fp_line
			(start 0.67945 0.3048)
			(end 0.120396 0.3048)
			(stroke
				(width 0.1)
				(type default)
			)
			(layer "F.Fab")
		)
		(fp_line
			(start 0.67945 -0.3048)
			(end 0.67945 0.3048)
			(stroke
				(width 0.1)
				(type default)
			)
			(layer "F.Fab")
		)
		(fp_line
			(start 0.12065 -0.2794)
			(end 0.12065 -0.3048)
			(stroke
				(width 0.1)
				(type default)
			)
			(layer "F.Fab")
		)
		(fp_line
			(start 0.12065 -0.3048)
			(end 0.67945 -0.3048)
			(stroke
				(width 0.1)
				(type default)
			)
			(layer "F.Fab")
		)
		(fp_line
			(start 0.120396 0.3048)
			(end 0.120396 0.2794)
			(stroke
				(width 0.1)
				(type default)
			)
			(layer "F.Fab")
		)
		(fp_line
			(start 0.120396 0.2794)
			(end -0.12065 0.2794)
			(stroke
				(width 0.1)
				(type default)
			)
			(layer "F.Fab")
		)
		(fp_line
			(start -0.12065 0.3048)
			(end -0.67945 0.3048)
			(stroke
				(width 0.1)
				(type default)
			)
			(layer "F.Fab")
		)
		(fp_line
			(start -0.12065 0.2794)
			(end -0.12065 0.3048)
			(stroke
				(width 0.1)
				(type default)
			)
			(layer "F.Fab")
		)
		(fp_line
			(start -0.12065 -0.2794)
			(end 0.12065 -0.2794)
			(stroke
				(width 0.1)
				(type default)
			)
			(layer "F.Fab")
		)
		(fp_line
			(start -0.12065 -0.305054)
			(end -0.12065 -0.2794)
			(stroke
				(width 0.1)
				(type default)
			)
			(layer "F.Fab")
		)
		(fp_line
			(start -0.67945 0.3048)
			(end -0.67945 -0.305054)
			(stroke
				(width 0.1)
				(type default)
			)
			(layer "F.Fab")
		)
		(fp_line
			(start -0.67945 -0.305054)
			(end -0.12065 -0.305054)
			(stroke
				(width 0.1)
				(type default)
			)
			(layer "F.Fab")
		)
		(pad "1" smd circle
			(at -0.40005 0 180)
			(size 0 0)
			(layers "F.Cu" "F.Mask" "F.Paste")
			(net "BIC_USB_HUB_XOUT_R")
		)
		(pad "2" smd circle
			(at 0.40005 0 180)
			(size 0 0)
			(layers "F.Cu" "F.Mask" "F.Paste")
			(net "GND")
		)
	)
	(footprint ""
		(layer "F.Cu")
		(at 132.142738 -279.486868 -90)
		(property "Reference" "PR114"
			(at 0 0 270)
			(layer "F.SilkS")
			(hide yes)
			(effects
				(font
					(size 1.27 1.27)
				)
			)
		)
		(property "Value" ""
			(at 0 0 270)
			(layer "F.Fab")
			(effects
				(font
					(size 1.27 1.27)
				)
			)
		)
		(duplicate_pad_numbers_are_jumpers no)
		(fp_line
			(start -0.7874 0.4064)
			(end -0.7874 -0.4064)
			(stroke
				(width 0.1524)
				(type default)
			)
			(layer "F.SilkS")
		)
		(fp_line
			(start 0.7874 0.4064)
			(end -0.7874 0.4064)
			(stroke
				(width 0.1524)
				(type default)
			)
			(layer "F.SilkS")
		)
		(fp_line
			(start -0.7874 -0.4064)
			(end 0.7874 -0.4064)
			(stroke
				(width 0.1524)
				(type default)
			)
			(layer "F.SilkS")
		)
		(fp_line
			(start 0.7874 -0.4064)
			(end 0.7874 0.4064)
			(stroke
				(width 0.1524)
				(type default)
			)
			(layer "F.SilkS")
		)
		(fp_line
			(start -0.67945 0.3048)
			(end -0.67945 -0.305054)
			(stroke
				(width 0.1)
				(type default)
			)
			(layer "F.Fab")
		)
		(fp_line
			(start -0.12065 0.3048)
			(end -0.67945 0.3048)
			(stroke
				(width 0.1)
				(type default)
			)
			(layer "F.Fab")
		)
		(fp_line
			(start 0.120396 0.3048)
			(end 0.120396 0.2794)
			(stroke
				(width 0.1)
				(type default)
			)
			(layer "F.Fab")
		)
		(fp_line
			(start 0.67945 0.3048)
			(end 0.120396 0.3048)
			(stroke
				(width 0.1)
				(type default)
			)
			(layer "F.Fab")
		)
		(fp_line
			(start -0.12065 0.2794)
			(end -0.12065 0.3048)
			(stroke
				(width 0.1)
				(type default)
			)
			(layer "F.Fab")
		)
		(fp_line
			(start 0.120396 0.2794)
			(end -0.12065 0.2794)
			(stroke
				(width 0.1)
				(type default)
			)
			(layer "F.Fab")
		)
		(fp_line
			(start -0.12065 -0.2794)
			(end 0.12065 -0.2794)
			(stroke
				(width 0.1)
				(type default)
			)
			(layer "F.Fab")
		)
		(fp_line
			(start 0.12065 -0.2794)
			(end 0.12065 -0.3048)
			(stroke
				(width 0.1)
				(type default)
			)
			(layer "F.Fab")
		)
		(fp_line
			(start 0.12065 -0.3048)
			(end 0.67945 -0.3048)
			(stroke
				(width 0.1)
				(type default)
			)
			(layer "F.Fab")
		)
		(fp_line
			(start 0.67945 -0.3048)
			(end 0.67945 0.3048)
			(stroke
				(width 0.1)
				(type default)
			)
			(layer "F.Fab")
		)
		(fp_line
			(start -0.67945 -0.305054)
			(end -0.12065 -0.305054)
			(stroke
				(width 0.1)
				(type default)
			)
			(layer "F.Fab")
		)
		(fp_line
			(start -0.12065 -0.305054)
			(end -0.12065 -0.2794)
			(stroke
				(width 0.1)
				(type default)
			)
			(layer "F.Fab")
		)
		(pad "1" smd circle
			(at -0.40005 0 270)
			(size 0 0)
			(layers "F.Cu" "F.Mask" "F.Paste")
			(net "P0V8_PEX1_LSET2")
		)
		(pad "2" smd circle
			(at 0.40005 0 270)
			(size 0 0)
			(layers "F.Cu" "F.Mask" "F.Paste")
			(net "GND")
		)
	)
	(footprint ""
		(layer "F.Cu")
		(at 198.76135 -155.196794 180)
		(property "Reference" "C213"
			(at 0 0 180)
			(layer "F.SilkS")
			(hide yes)
			(effects
				(font
					(size 1.27 1.27)
				)
			)
		)
		(property "Value" ""
			(at 0 0 180)
			(layer "F.Fab")
			(effects
				(font
					(size 1.27 1.27)
				)
			)
		)
		(duplicate_pad_numbers_are_jumpers no)
		(fp_line
			(start 0.299974 0.150114)
			(end -0.299974 0.150114)
			(stroke
				(width 0.1)
				(type default)
			)
			(layer "F.Fab")
		)
		(fp_line
			(start 0.299974 -0.150114)
			(end 0.299974 0.150114)
			(stroke
				(width 0.1)
				(type default)
			)
			(layer "F.Fab")
		)
		(fp_line
			(start -0.299974 0.150114)
			(end -0.299974 -0.150114)
			(stroke
				(width 0.1)
				(type default)
			)
			(layer "F.Fab")
		)
		(fp_line
			(start -0.299974 -0.150114)
			(end 0.299974 -0.150114)
			(stroke
				(width 0.1)
				(type default)
			)
			(layer "F.Fab")
		)
		(pad "1" smd rect
			(at -0.2667 0 180)
			(size 0.3048 0.381)
			(layers "F.Cu" "F.Mask" "F.Paste")
			(net "P5E_PEX1_STN0_TX_DN<15>")
		)
		(pad "2" smd rect
			(at 0.2667 0 180)
			(size 0.3048 0.381)
			(layers "F.Cu" "F.Mask" "F.Paste")
			(net "P5E_PEX1_STN0_TX_C_DN<15>")
		)
	)
	(footprint ""
		(layer "F.Cu")
		(at 360.794808 -157.304994 -90)
		(property "Reference" "PU105"
			(at 3.839464 1.638808 0)
			(unlocked yes)
			(layer "F.SilkS")
			(effects
				(font
					(size 0.7874 0.5842)
					(thickness 0.1524)
				)
				(justify left)
			)
		)
		(property "Value" ""
			(at 0 0 270)
			(layer "F.Fab")
			(effects
				(font
					(size 1.27 1.27)
				)
			)
		)
		(duplicate_pad_numbers_are_jumpers no)
		(fp_line
			(start -1.549908 2.549906)
			(end -0.753872 2.549906)
			(stroke
				(width 0.1524)
				(type default)
			)
			(layer "F.SilkS")
		)
		(fp_line
			(start -0.245872 2.549906)
			(end 0.245872 2.549906)
			(stroke
				(width 0.1524)
				(type default)
			)
			(layer "F.SilkS")
		)
		(fp_line
			(start 0.753872 2.549906)
			(end 1.549908 2.549906)
			(stroke
				(width 0.1524)
				(type default)
			)
			(layer "F.SilkS")
		)
		(fp_line
			(start 1.549908 2.549906)
			(end 1.549908 2.253996)
			(stroke
				(width 0.1524)
				(type default)
			)
			(layer "F.SilkS")
		)
		(fp_line
			(start -1.549908 2.253996)
			(end -1.549908 2.549906)
			(stroke
				(width 0.1524)
				(type default)
			)
			(layer "F.SilkS")
		)
		(fp_line
			(start 1.549908 -2.253996)
			(end 1.549908 -2.549906)
			(stroke
				(width 0.1524)
				(type default)
			)
			(layer "F.SilkS")
		)
		(fp_line
			(start -1.549908 -2.549906)
			(end -1.549908 -2.251964)
			(stroke
				(width 0.1524)
				(type default)
			)
			(layer "F.SilkS")
		)
		(fp_line
			(start -0.752094 -2.549906)
			(end -1.549908 -2.549906)
			(stroke
				(width 0.1524)
				(type default)
			)
			(layer "F.SilkS")
		)
		(fp_line
			(start 0.2413 -2.549906)
			(end -0.2413 -2.549906)
			(stroke
				(width 0.1524)
				(type default)
			)
			(layer "F.SilkS")
		)
		(fp_line
			(start 1.549908 -2.549906)
			(end 0.752094 -2.549906)
			(stroke
				(width 0.1524)
				(type default)
			)
			(layer "F.SilkS")
		)
		(fp_poly
			(pts
				(xy -2.312162 -2.109724) (xy -3.163824 -1.68402) (xy -3.163824 -2.535428)
			)
			(stroke
				(width 0)
				(type default)
			)
			(fill yes)
			(layer "F.SilkS")
		)
		(fp_line
			(start -1.549908 2.549906)
			(end 1.549908 2.549906)
			(stroke
				(width 0.1)
				(type default)
			)
			(layer "F.Fab")
		)
		(fp_line
			(start 1.549908 2.549906)
			(end 1.549908 -2.549906)
			(stroke
				(width 0.1)
				(type default)
			)
			(layer "F.Fab")
		)
		(fp_line
			(start -1.549908 -2.549906)
			(end -1.549908 2.549906)
			(stroke
				(width 0.1)
				(type default)
			)
			(layer "F.Fab")
		)
		(fp_line
			(start 1.549908 -2.549906)
			(end -1.549908 -2.549906)
			(stroke
				(width 0.1)
				(type default)
			)
			(layer "F.Fab")
		)
		(fp_poly
			(pts
				(xy -1.891538 -1.999996) (xy -2.7432 -1.574292) (xy -2.7432 -2.4257)
			)
			(stroke
				(width 0)
				(type default)
			)
			(fill yes)
			(layer "F.Fab")
		)
		(fp_text user "11"
			(at 1.215644 3.135884 270)
			(unlocked yes)
			(layer "F.SilkS")
			(effects
				(font
					(size 0.635 0.4064)
					(thickness 0.1524)
				)
			)
		)
		(fp_text user "10"
			(at -1.409446 3.12039 0)
			(unlocked yes)
			(layer "F.SilkS")
			(effects
				(font
					(size 0.635 0.4064)
					(thickness 0.1524)
				)
			)
		)
		(fp_text user "12"
			(at 2.176018 2.903728 0)
			(unlocked yes)
			(layer "F.SilkS")
			(effects
				(font
					(size 0.635 0.4064)
					(thickness 0.1524)
				)
			)
		)
		(fp_text user "9"
			(at -2.338832 2.5908 180)
			(unlocked yes)
			(layer "F.SilkS")
			(effects
				(font
					(size 0.635 0.4064)
					(thickness 0.1524)
				)
			)
		)
		(fp_text user "20"
			(at 1.820164 -3.10642 0)
			(unlocked yes)
			(layer "F.SilkS")
			(effects
				(font
					(size 0.635 0.4064)
					(thickness 0.1524)
				)
			)
		)
		(fp_text user "21_22"
			(at 0.307848 -3.987038 270)
			(unlocked yes)
			(layer "F.SilkS")
			(effects
				(font
					(size 0.635 0.4064)
					(thickness 0.1524)
				)
			)
		)
		(fp_text user "11"
			(at 1.1938 3.329432 270)
			(unlocked yes)
			(layer "F.Fab")
			(effects
				(font
					(size 0.635 0.4064)
					(thickness 0.1524)
				)
			)
		)
		(fp_text user "10"
			(at -1.4224 3.253232 270)
			(unlocked yes)
			(layer "F.Fab")
			(effects
				(font
					(size 0.635 0.4064)
					(thickness 0.1524)
				)
			)
		)
		(fp_text user "12"
			(at 2.207768 2.7178 180)
			(unlocked yes)
			(layer "F.Fab")
			(effects
				(font
					(size 0.635 0.4064)
					(thickness 0.1524)
				)
			)
		)
		(fp_text user "9"
			(at -2.338832 2.5908 180)
			(unlocked yes)
			(layer "F.Fab")
			(effects
				(font
					(size 0.635 0.4064)
					(thickness 0.1524)
				)
			)
		)
		(fp_text user "20"
			(at 2.055368 -2.7686 180)
			(unlocked yes)
			(layer "F.Fab")
			(effects
				(font
					(size 0.635 0.4064)
					(thickness 0.1524)
				)
			)
		)
		(fp_text user "21_22"
			(at -0.0762 -3.401568 270)
			(unlocked yes)
			(layer "F.Fab")
			(effects
				(font
					(size 0.635 0.4064)
					(thickness 0.1524)
				)
			)
		)
		(pad "1" smd circle
			(at -1.374902 -1.999996 180)
			(size 0 0)
			(layers "F.Cu" "F.Mask" "F.Paste")
			(net "P12V_NIC6_CO_EN")
		)
		(pad "2" smd rect
			(at -1.400048 -1.500124 180)
			(size 0.254 0.8128)
			(layers "F.Cu" "F.Mask" "F.Paste")
			(net "GND")
		)
		(pad "3" smd rect
			(at -1.400048 -0.999998 180)
			(size 0.254 0.8128)
			(layers "F.Cu" "F.Mask" "F.Paste")
			(net "GND")
		)
		(pad "4" smd rect
			(at -1.400048 -0.499872 180)
			(size 0.254 0.8128)
			(layers "F.Cu" "F.Mask" "F.Paste")
			(net "P12V_NIC6_CO_TIMER")
		)
		(pad "5" smd rect
			(at -1.400048 0 180)
			(size 0.254 0.8128)
			(layers "F.Cu" "F.Mask" "F.Paste")
			(net "P12V_NIC6_CO_ISET")
		)
		(pad "6" smd rect
			(at -1.400048 0.499872 180)
			(size 0.254 0.8128)
			(layers "F.Cu" "F.Mask" "F.Paste")
			(net "P12V_NIC6_CO_SS")
		)
		(pad "7" smd rect
			(at -1.400048 0.999998 180)
			(size 0.254 0.8128)
			(layers "F.Cu" "F.Mask" "F.Paste")
			(net "GND")
		)
		(pad "8" smd rect
			(at -1.400048 1.500124 180)
			(size 0.254 0.8128)
			(layers "F.Cu" "F.Mask" "F.Paste")
			(net "P12V_NIC6_CO_IMON_VR")
		)
		(pad "9" smd rect
			(at -1.400048 1.999996 180)
			(size 0.254 0.8128)
			(layers "F.Cu" "F.Mask" "F.Paste")
			(net "P12V_NIC6_CO_FLTB")
		)
		(pad "10" smd rect
			(at -0.499872 2.400046 270)
			(size 0.254 0.8128)
			(layers "F.Cu" "F.Mask" "F.Paste")
			(net "PWRGD_P12V_NIC6_CO")
		)
		(pad "11" smd rect
			(at 0.499872 2.400046 270)
			(size 0.254 0.8128)
			(layers "F.Cu" "F.Mask" "F.Paste")
			(net "P12V_NIC6_CO_OV_FB")
		)
		(pad "12" smd rect
			(at 1.400048 1.999996 180)
			(size 0.254 0.8128)
			(layers "F.Cu" "F.Mask" "F.Paste")
			(net "P12V_NIC6_CO_AVIN_PD")
		)
		(pad "13" smd rect
			(at 1.400048 1.500124 180)
			(size 0.254 0.8128)
			(layers "F.Cu" "F.Mask" "F.Paste")
			(net "P12V_NIC6_R")
		)
		(pad "14" smd rect
			(at 1.400048 0.999998 180)
			(size 0.254 0.8128)
			(layers "F.Cu" "F.Mask" "F.Paste")
			(net "P12V_NIC6_R")
		)
		(pad "15" smd rect
			(at 1.400048 0.499872 180)
			(size 0.254 0.8128)
			(layers "F.Cu" "F.Mask" "F.Paste")
			(net "P12V_NIC6_R")
		)
		(pad "16" smd rect
			(at 1.400048 0 180)
			(size 0.254 0.8128)
			(layers "F.Cu" "F.Mask" "F.Paste")
			(net "P12V_NIC6_R")
		)
		(pad "17" smd rect
			(at 1.400048 -0.499872 180)
			(size 0.254 0.8128)
			(layers "F.Cu" "F.Mask" "F.Paste")
			(net "P12V_NIC6_R")
		)
		(pad "18" smd rect
			(at 1.400048 -0.999998 180)
			(size 0.254 0.8128)
			(layers "F.Cu" "F.Mask" "F.Paste")
			(net "P12V_NIC6_R")
		)
		(pad "19" smd rect
			(at 1.400048 -1.500124 180)
			(size 0.254 0.8128)
			(layers "F.Cu" "F.Mask" "F.Paste")
			(net "P12V_NIC6_R")
		)
		(pad "20" smd rect
			(at 1.400048 -1.999996 180)
			(size 0.254 0.8128)
			(layers "F.Cu" "F.Mask" "F.Paste")
			(net "P12V_NIC6_R")
		)
		(pad "21_22" smd circle
			(at 0.499872 -2.337562 180)
			(size 0 0)
			(layers "F.Cu" "F.Mask" "F.Paste")
			(net "P12V_AUX")
		)
		(pad "23" smd rect
			(at 0 -1.100074 180)
			(size 0.254 1.27)
			(layers "F.Cu" "F.Mask" "F.Paste")
			(net "P12V_AUX")
		)
		(pad "24" smd rect
			(at 0 -0.199898 180)
			(size 0.254 1.27)
			(layers "F.Cu" "F.Mask" "F.Paste")
			(net "P12V_AUX")
		)
		(pad "25" smd rect
			(at 0 0.700024 180)
			(size 0.254 1.27)
			(layers "F.Cu" "F.Mask" "F.Paste")
			(net "P12V_AUX")
		)
		(pad "26" smd rect
			(at 0 1.599946 180)
			(size 0.254 1.27)
			(layers "F.Cu" "F.Mask" "F.Paste")
			(net "P12V_AUX")
		)
	)
	(footprint ""
		(layer "F.Cu")
		(at 227.008944 -98.36912 -90)
		(property "Reference" "C2859"
			(at 0 0 270)
			(layer "F.SilkS")
			(hide yes)
			(effects
				(font
					(size 1.27 1.27)
				)
			)
		)
		(property "Value" ""
			(at 0 0 270)
			(layer "F.Fab")
			(effects
				(font
					(size 1.27 1.27)
				)
			)
		)
		(duplicate_pad_numbers_are_jumpers no)
		(fp_line
			(start -0.7874 0.4064)
			(end -0.7874 -0.4064)
			(stroke
				(width 0.1524)
				(type default)
			)
			(layer "F.SilkS")
		)
		(fp_line
			(start 0.7874 0.4064)
			(end -0.7874 0.4064)
			(stroke
				(width 0.1524)
				(type default)
			)
			(layer "F.SilkS")
		)
		(fp_line
			(start -0.7874 -0.4064)
			(end 0.7874 -0.4064)
			(stroke
				(width 0.1524)
				(type default)
			)
			(layer "F.SilkS")
		)
		(fp_line
			(start 0.7874 -0.4064)
			(end 0.7874 0.4064)
			(stroke
				(width 0.1524)
				(type default)
			)
			(layer "F.SilkS")
		)
		(fp_line
			(start -0.67945 0.3048)
			(end -0.67945 -0.305054)
			(stroke
				(width 0.1)
				(type default)
			)
			(layer "F.Fab")
		)
		(fp_line
			(start -0.12065 0.3048)
			(end -0.67945 0.3048)
			(stroke
				(width 0.1)
				(type default)
			)
			(layer "F.Fab")
		)
		(fp_line
			(start 0.120396 0.3048)
			(end 0.120396 0.2794)
			(stroke
				(width 0.1)
				(type default)
			)
			(layer "F.Fab")
		)
		(fp_line
			(start 0.67945 0.3048)
			(end 0.120396 0.3048)
			(stroke
				(width 0.1)
				(type default)
			)
			(layer "F.Fab")
		)
		(fp_line
			(start -0.12065 0.2794)
			(end -0.12065 0.3048)
			(stroke
				(width 0.1)
				(type default)
			)
			(layer "F.Fab")
		)
		(fp_line
			(start 0.120396 0.2794)
			(end -0.12065 0.2794)
			(stroke
				(width 0.1)
				(type default)
			)
			(layer "F.Fab")
		)
		(fp_line
			(start -0.12065 -0.2794)
			(end 0.12065 -0.2794)
			(stroke
				(width 0.1)
				(type default)
			)
			(layer "F.Fab")
		)
		(fp_line
			(start 0.12065 -0.2794)
			(end 0.12065 -0.3048)
			(stroke
				(width 0.1)
				(type default)
			)
			(layer "F.Fab")
		)
		(fp_line
			(start 0.12065 -0.3048)
			(end 0.67945 -0.3048)
			(stroke
				(width 0.1)
				(type default)
			)
			(layer "F.Fab")
		)
		(fp_line
			(start 0.67945 -0.3048)
			(end 0.67945 0.3048)
			(stroke
				(width 0.1)
				(type default)
			)
			(layer "F.Fab")
		)
		(fp_line
			(start -0.67945 -0.305054)
			(end -0.12065 -0.305054)
			(stroke
				(width 0.1)
				(type default)
			)
			(layer "F.Fab")
		)
		(fp_line
			(start -0.12065 -0.305054)
			(end -0.12065 -0.2794)
			(stroke
				(width 0.1)
				(type default)
			)
			(layer "F.Fab")
		)
		(pad "1" smd circle
			(at -0.40005 0 270)
			(size 0 0)
			(layers "F.Cu" "F.Mask" "F.Paste")
			(net "P12V_NIC3_EN_R")
		)
		(pad "2" smd circle
			(at 0.40005 0 270)
			(size 0 0)
			(layers "F.Cu" "F.Mask" "F.Paste")
			(net "GND")
		)
	)
)
